(kicad_pcb
	(version 20260206)
	(generator "pcbnew")
	(generator_version "10.0")
	(general
		(thickness 1.6)
		(legacy_teardrops no)
	)
	(paper "A4")
	(title_block
		(title "01162023_DA0F0TEBIF0_F0T_Expander_BD_F_brd_V02_OCP.brd")
		(comment 1 "Grand Teton / footprints 4128-4136 of 9728")
	)
	(layers
		(0 "F.Cu" signal "TOP")
		(4 "In1.Cu" signal "GND")
		(6 "In2.Cu" signal "VCC")
		(8 "In3.Cu" signal "VCC1")
		(10 "In4.Cu" signal "GND1")
		(12 "In5.Cu" signal "IN1")
		(14 "In6.Cu" signal "GND2")
		(16 "In7.Cu" signal "IN2")
		(18 "In8.Cu" signal "GND3")
		(20 "In9.Cu" signal "IN3")
		(22 "In10.Cu" signal "GND4")
		(24 "In11.Cu" signal "IN4")
		(26 "In12.Cu" signal "GND5")
		(28 "In13.Cu" signal "IN5")
		(30 "In14.Cu" signal "GND6")
		(32 "In15.Cu" signal "IN6")
		(34 "In16.Cu" signal "GND7")
		(2 "B.Cu" signal "BOTTOM")
		(9 "F.Adhes" user "F.Adhesive")
		(11 "B.Adhes" user "B.Adhesive")
		(13 "F.Paste" user "Package Geometry/Pastemask Top")
		(15 "B.Paste" user "Package Geometry/Pastemask Bottom")
		(5 "F.SilkS" user "Ref Des/Silkscreen Top")
		(7 "B.SilkS" user "Ref Des/Silkscreen Bottom")
		(1 "F.Mask" user "Board Geometry/Soldermask Top")
		(3 "B.Mask" user "Board Geometry/Soldermask Bottom")
		(17 "Dwgs.User" user "User.Drawings")
		(19 "Cmts.User" user "User.Comments")
		(21 "Eco1.User" user "User.Eco1")
		(23 "Eco2.User" user "User.Eco2")
		(25 "Edge.Cuts" user "Board Geometry/Outline")
		(27 "Margin" user)
		(31 "F.CrtYd" user "Package Geometry/Place Bound Top")
		(29 "B.CrtYd" user "Package Geometry/Place Bound Bottom")
		(35 "F.Fab" user "Ref Des/Assembly Top")
		(33 "B.Fab" user "Ref Des/Assembly Bottom")
	)
	(footprint ""
		(layer "F.Cu")
		(at 115.64239 -257.13055 180)
		(property "Reference" "PC56"
			(at 0 0 180)
			(layer "F.SilkS")
			(hide yes)
			(effects
				(font
					(size 1.27 1.27)
				)
			)
		)
		(property "Value" ""
			(at 0 0 180)
			(layer "F.Fab")
			(effects
				(font
					(size 1.27 1.27)
				)
			)
		)
		(duplicate_pad_numbers_are_jumpers no)
		(fp_line
			(start 0.7874 0.4064)
			(end -0.7874 0.4064)
			(stroke
				(width 0.1524)
				(type default)
			)
			(layer "F.SilkS")
		)
		(fp_line
			(start 0.7874 -0.4064)
			(end 0.7874 0.4064)
			(stroke
				(width 0.1524)
				(type default)
			)
			(layer "F.SilkS")
		)
		(fp_line
			(start -0.7874 0.4064)
			(end -0.7874 -0.4064)
			(stroke
				(width 0.1524)
				(type default)
			)
			(layer "F.SilkS")
		)
		(fp_line
			(start -0.7874 -0.4064)
			(end 0.7874 -0.4064)
			(stroke
				(width 0.1524)
				(type default)
			)
			(layer "F.SilkS")
		)
		(fp_line
			(start 0.67945 0.3048)
			(end 0.120396 0.3048)
			(stroke
				(width 0.1)
				(type default)
			)
			(layer "F.Fab")
		)
		(fp_line
			(start 0.67945 -0.3048)
			(end 0.67945 0.3048)
			(stroke
				(width 0.1)
				(type default)
			)
			(layer "F.Fab")
		)
		(fp_line
			(start 0.12065 -0.2794)
			(end 0.12065 -0.3048)
			(stroke
				(width 0.1)
				(type default)
			)
			(layer "F.Fab")
		)
		(fp_line
			(start 0.12065 -0.3048)
			(end 0.67945 -0.3048)
			(stroke
				(width 0.1)
				(type default)
			)
			(layer "F.Fab")
		)
		(fp_line
			(start 0.120396 0.3048)
			(end 0.120396 0.2794)
			(stroke
				(width 0.1)
				(type default)
			)
			(layer "F.Fab")
		)
		(fp_line
			(start 0.120396 0.2794)
			(end -0.12065 0.2794)
			(stroke
				(width 0.1)
				(type default)
			)
			(layer "F.Fab")
		)
		(fp_line
			(start -0.12065 0.3048)
			(end -0.67945 0.3048)
			(stroke
				(width 0.1)
				(type default)
			)
			(layer "F.Fab")
		)
		(fp_line
			(start -0.12065 0.2794)
			(end -0.12065 0.3048)
			(stroke
				(width 0.1)
				(type default)
			)
			(layer "F.Fab")
		)
		(fp_line
			(start -0.12065 -0.2794)
			(end 0.12065 -0.2794)
			(stroke
				(width 0.1)
				(type default)
			)
			(layer "F.Fab")
		)
		(fp_line
			(start -0.12065 -0.305054)
			(end -0.12065 -0.2794)
			(stroke
				(width 0.1)
				(type default)
			)
			(layer "F.Fab")
		)
		(fp_line
			(start -0.67945 0.3048)
			(end -0.67945 -0.305054)
			(stroke
				(width 0.1)
				(type default)
			)
			(layer "F.Fab")
		)
		(fp_line
			(start -0.67945 -0.305054)
			(end -0.12065 -0.305054)
			(stroke
				(width 0.1)
				(type default)
			)
			(layer "F.Fab")
		)
		(pad "1" smd circle
			(at -0.40005 0 180)
			(size 0 0)
			(layers "F.Cu" "F.Mask" "F.Paste")
			(net "P0V8_PEX0_VINSEN")
		)
		(pad "2" smd circle
			(at 0.40005 0 180)
			(size 0 0)
			(layers "F.Cu" "F.Mask" "F.Paste")
			(net "GND")
		)
	)
	(footprint ""
		(layer "F.Cu")
		(at 428.319438 -154.304746 180)
		(property "Reference" "C636"
			(at 0 0 180)
			(layer "F.SilkS")
			(hide yes)
			(effects
				(font
					(size 1.27 1.27)
				)
			)
		)
		(property "Value" ""
			(at 0 0 180)
			(layer "F.Fab")
			(effects
				(font
					(size 1.27 1.27)
				)
			)
		)
		(duplicate_pad_numbers_are_jumpers no)
		(fp_line
			(start 0.299974 0.150114)
			(end -0.299974 0.150114)
			(stroke
				(width 0.1)
				(type default)
			)
			(layer "F.Fab")
		)
		(fp_line
			(start 0.299974 -0.150114)
			(end 0.299974 0.150114)
			(stroke
				(width 0.1)
				(type default)
			)
			(layer "F.Fab")
		)
		(fp_line
			(start -0.299974 0.150114)
			(end -0.299974 -0.150114)
			(stroke
				(width 0.1)
				(type default)
			)
			(layer "F.Fab")
		)
		(fp_line
			(start -0.299974 -0.150114)
			(end 0.299974 -0.150114)
			(stroke
				(width 0.1)
				(type default)
			)
			(layer "F.Fab")
		)
		(pad "1" smd rect
			(at -0.2667 0 180)
			(size 0.3048 0.381)
			(layers "F.Cu" "F.Mask" "F.Paste")
			(net "P5E_PEX3_STN0_TX_DN<14>")
		)
		(pad "2" smd rect
			(at 0.2667 0 180)
			(size 0.3048 0.381)
			(layers "F.Cu" "F.Mask" "F.Paste")
			(net "P5E_PEX3_STN0_TX_C_DN<14>")
		)
	)
	(footprint ""
		(layer "F.Cu")
		(at 268.838426 -119.198898)
		(property "Reference" "C469"
			(at 0 0 0)
			(layer "F.SilkS")
			(hide yes)
			(effects
				(font
					(size 1.27 1.27)
				)
			)
		)
		(property "Value" ""
			(at 0 0 0)
			(layer "F.Fab")
			(effects
				(font
					(size 1.27 1.27)
				)
			)
		)
		(duplicate_pad_numbers_are_jumpers no)
		(fp_line
			(start -0.299974 -0.150114)
			(end 0.299974 -0.150114)
			(stroke
				(width 0.1)
				(type default)
			)
			(layer "F.Fab")
		)
		(fp_line
			(start -0.299974 0.150114)
			(end -0.299974 -0.150114)
			(stroke
				(width 0.1)
				(type default)
			)
			(layer "F.Fab")
		)
		(fp_line
			(start 0.299974 -0.150114)
			(end 0.299974 0.150114)
			(stroke
				(width 0.1)
				(type default)
			)
			(layer "F.Fab")
		)
		(fp_line
			(start 0.299974 0.150114)
			(end -0.299974 0.150114)
			(stroke
				(width 0.1)
				(type default)
			)
			(layer "F.Fab")
		)
		(pad "1" smd rect
			(at -0.2667 0)
			(size 0.3048 0.381)
			(layers "F.Cu" "F.Mask" "F.Paste")
			(net "P5E_PEX2_STN1_TX_DP<24>")
		)
		(pad "2" smd rect
			(at 0.2667 0)
			(size 0.3048 0.381)
			(layers "F.Cu" "F.Mask" "F.Paste")
			(net "P5E_PEX2_STN1_TX_C_DP<24>")
		)
	)
	(footprint ""
		(layer "F.Cu")
		(at 344.612976 -88.16975 180)
		(property "Reference" "R1181"
			(at 0 0 180)
			(layer "F.SilkS")
			(hide yes)
			(effects
				(font
					(size 1.27 1.27)
				)
			)
		)
		(property "Value" ""
			(at 0 0 180)
			(layer "F.Fab")
			(effects
				(font
					(size 1.27 1.27)
				)
			)
		)
		(duplicate_pad_numbers_are_jumpers no)
		(fp_line
			(start 0.7874 0.4064)
			(end -0.7874 0.4064)
			(stroke
				(width 0.1524)
				(type default)
			)
			(layer "F.SilkS")
		)
		(fp_line
			(start 0.67945 0.3048)
			(end 0.120396 0.3048)
			(stroke
				(width 0.1)
				(type default)
			)
			(layer "F.Fab")
		)
		(fp_line
			(start 0.67945 -0.3048)
			(end 0.67945 0.3048)
			(stroke
				(width 0.1)
				(type default)
			)
			(layer "F.Fab")
		)
		(fp_line
			(start 0.12065 -0.2794)
			(end 0.12065 -0.3048)
			(stroke
				(width 0.1)
				(type default)
			)
			(layer "F.Fab")
		)
		(fp_line
			(start 0.12065 -0.3048)
			(end 0.67945 -0.3048)
			(stroke
				(width 0.1)
				(type default)
			)
			(layer "F.Fab")
		)
		(fp_line
			(start 0.120396 0.3048)
			(end 0.120396 0.2794)
			(stroke
				(width 0.1)
				(type default)
			)
			(layer "F.Fab")
		)
		(fp_line
			(start 0.120396 0.2794)
			(end -0.12065 0.2794)
			(stroke
				(width 0.1)
				(type default)
			)
			(layer "F.Fab")
		)
		(fp_line
			(start -0.12065 0.3048)
			(end -0.67945 0.3048)
			(stroke
				(width 0.1)
				(type default)
			)
			(layer "F.Fab")
		)
		(fp_line
			(start -0.12065 0.2794)
			(end -0.12065 0.3048)
			(stroke
				(width 0.1)
				(type default)
			)
			(layer "F.Fab")
		)
		(fp_line
			(start -0.12065 -0.2794)
			(end 0.12065 -0.2794)
			(stroke
				(width 0.1)
				(type default)
			)
			(layer "F.Fab")
		)
		(fp_line
			(start -0.12065 -0.305054)
			(end -0.12065 -0.2794)
			(stroke
				(width 0.1)
				(type default)
			)
			(layer "F.Fab")
		)
		(fp_line
			(start -0.67945 0.3048)
			(end -0.67945 -0.305054)
			(stroke
				(width 0.1)
				(type default)
			)
			(layer "F.Fab")
		)
		(fp_line
			(start -0.67945 -0.305054)
			(end -0.12065 -0.305054)
			(stroke
				(width 0.1)
				(type default)
			)
			(layer "F.Fab")
		)
		(pad "1" smd circle
			(at -0.40005 0 180)
			(size 0 0)
			(layers "F.Cu" "F.Mask" "F.Paste")
			(net "CLK_100M_DB800ZL_SSD13_R_DN")
		)
		(pad "2" smd circle
			(at 0.40005 0 180)
			(size 0 0)
			(layers "F.Cu" "F.Mask" "F.Paste")
			(net "CLK_100M_DB800ZL_SSD13_DN")
		)
	)
	(footprint ""
		(layer "F.Cu")
		(at 230.938832 -155.960826 -90)
		(property "Reference" "R1207"
			(at 0 0 270)
			(layer "F.SilkS")
			(hide yes)
			(effects
				(font
					(size 1.27 1.27)
				)
			)
		)
		(property "Value" ""
			(at 0 0 270)
			(layer "F.Fab")
			(effects
				(font
					(size 1.27 1.27)
				)
			)
		)
		(duplicate_pad_numbers_are_jumpers no)
		(fp_line
			(start 0.7874 0.4064)
			(end -0.7874 0.4064)
			(stroke
				(width 0.1524)
				(type default)
			)
			(layer "F.SilkS")
		)
		(fp_line
			(start -0.67945 0.3048)
			(end -0.67945 -0.305054)
			(stroke
				(width 0.1)
				(type default)
			)
			(layer "F.Fab")
		)
		(fp_line
			(start -0.12065 0.3048)
			(end -0.67945 0.3048)
			(stroke
				(width 0.1)
				(type default)
			)
			(layer "F.Fab")
		)
		(fp_line
			(start 0.120396 0.3048)
			(end 0.120396 0.2794)
			(stroke
				(width 0.1)
				(type default)
			)
			(layer "F.Fab")
		)
		(fp_line
			(start 0.67945 0.3048)
			(end 0.120396 0.3048)
			(stroke
				(width 0.1)
				(type default)
			)
			(layer "F.Fab")
		)
		(fp_line
			(start -0.12065 0.2794)
			(end -0.12065 0.3048)
			(stroke
				(width 0.1)
				(type default)
			)
			(layer "F.Fab")
		)
		(fp_line
			(start 0.120396 0.2794)
			(end -0.12065 0.2794)
			(stroke
				(width 0.1)
				(type default)
			)
			(layer "F.Fab")
		)
		(fp_line
			(start -0.12065 -0.2794)
			(end 0.12065 -0.2794)
			(stroke
				(width 0.1)
				(type default)
			)
			(layer "F.Fab")
		)
		(fp_line
			(start 0.12065 -0.2794)
			(end 0.12065 -0.3048)
			(stroke
				(width 0.1)
				(type default)
			)
			(layer "F.Fab")
		)
		(fp_line
			(start 0.12065 -0.3048)
			(end 0.67945 -0.3048)
			(stroke
				(width 0.1)
				(type default)
			)
			(layer "F.Fab")
		)
		(fp_line
			(start 0.67945 -0.3048)
			(end 0.67945 0.3048)
			(stroke
				(width 0.1)
				(type default)
			)
			(layer "F.Fab")
		)
		(fp_line
			(start -0.67945 -0.305054)
			(end -0.12065 -0.305054)
			(stroke
				(width 0.1)
				(type default)
			)
			(layer "F.Fab")
		)
		(fp_line
			(start -0.12065 -0.305054)
			(end -0.12065 -0.2794)
			(stroke
				(width 0.1)
				(type default)
			)
			(layer "F.Fab")
		)
		(pad "1" smd circle
			(at -0.40005 0 270)
			(size 0 0)
			(layers "F.Cu" "F.Mask" "F.Paste")
			(net "CLK_100M_PEX1_REF_R_DP")
		)
		(pad "2" smd circle
			(at 0.40005 0 270)
			(size 0 0)
			(layers "F.Cu" "F.Mask" "F.Paste")
			(net "CLK_100M_PEX1_REF_DP")
		)
	)
	(footprint ""
		(layer "F.Cu")
		(at 8.45058 -72.459088)
		(property "Reference" "R5655"
			(at 0 0 0)
			(layer "F.SilkS")
			(hide yes)
			(effects
				(font
					(size 1.27 1.27)
				)
			)
		)
		(property "Value" ""
			(at 0 0 0)
			(layer "F.Fab")
			(effects
				(font
					(size 1.27 1.27)
				)
			)
		)
		(duplicate_pad_numbers_are_jumpers no)
		(fp_line
			(start -0.7874 -0.4064)
			(end 0.7874 -0.4064)
			(stroke
				(width 0.1524)
				(type default)
			)
			(layer "F.SilkS")
		)
		(fp_line
			(start -0.7874 0.4064)
			(end -0.7874 -0.4064)
			(stroke
				(width 0.1524)
				(type default)
			)
			(layer "F.SilkS")
		)
		(fp_line
			(start 0.7874 -0.4064)
			(end 0.7874 0.4064)
			(stroke
				(width 0.1524)
				(type default)
			)
			(layer "F.SilkS")
		)
		(fp_line
			(start 0.7874 0.4064)
			(end -0.7874 0.4064)
			(stroke
				(width 0.1524)
				(type default)
			)
			(layer "F.SilkS")
		)
		(fp_line
			(start -0.67945 -0.305054)
			(end -0.12065 -0.305054)
			(stroke
				(width 0.1)
				(type default)
			)
			(layer "F.Fab")
		)
		(fp_line
			(start -0.67945 0.3048)
			(end -0.67945 -0.305054)
			(stroke
				(width 0.1)
				(type default)
			)
			(layer "F.Fab")
		)
		(fp_line
			(start -0.12065 -0.305054)
			(end -0.12065 -0.2794)
			(stroke
				(width 0.1)
				(type default)
			)
			(layer "F.Fab")
		)
		(fp_line
			(start -0.12065 -0.2794)
			(end 0.12065 -0.2794)
			(stroke
				(width 0.1)
				(type default)
			)
			(layer "F.Fab")
		)
		(fp_line
			(start -0.12065 0.2794)
			(end -0.12065 0.3048)
			(stroke
				(width 0.1)
				(type default)
			)
			(layer "F.Fab")
		)
		(fp_line
			(start -0.12065 0.3048)
			(end -0.67945 0.3048)
			(stroke
				(width 0.1)
				(type default)
			)
			(layer "F.Fab")
		)
		(fp_line
			(start 0.120396 0.2794)
			(end -0.12065 0.2794)
			(stroke
				(width 0.1)
				(type default)
			)
			(layer "F.Fab")
		)
		(fp_line
			(start 0.120396 0.3048)
			(end 0.120396 0.2794)
			(stroke
				(width 0.1)
				(type default)
			)
			(layer "F.Fab")
		)
		(fp_line
			(start 0.12065 -0.3048)
			(end 0.67945 -0.3048)
			(stroke
				(width 0.1)
				(type default)
			)
			(layer "F.Fab")
		)
		(fp_line
			(start 0.12065 -0.2794)
			(end 0.12065 -0.3048)
			(stroke
				(width 0.1)
				(type default)
			)
			(layer "F.Fab")
		)
		(fp_line
			(start 0.67945 -0.3048)
			(end 0.67945 0.3048)
			(stroke
				(width 0.1)
				(type default)
			)
			(layer "F.Fab")
		)
		(fp_line
			(start 0.67945 0.3048)
			(end 0.120396 0.3048)
			(stroke
				(width 0.1)
				(type default)
			)
			(layer "F.Fab")
		)
		(pad "1" smd circle
			(at -0.40005 0)
			(size 0 0)
			(layers "F.Cu" "F.Mask" "F.Paste")
			(net "RST_SMB_SSD0_ISO_N")
		)
		(pad "2" smd circle
			(at 0.40005 0)
			(size 0 0)
			(layers "F.Cu" "F.Mask" "F.Paste")
			(net "GND")
		)
	)
	(footprint ""
		(layer "F.Cu")
		(at 192.374012 -26.31186 -90)
		(property "Reference" "U404"
			(at -0.20574 -2.394458 90)
			(unlocked yes)
			(layer "F.SilkS")
			(effects
				(font
					(size 0.7874 0.5842)
					(thickness 0.1524)
				)
			)
		)
		(property "Value" ""
			(at 0 0 270)
			(layer "F.Fab")
			(effects
				(font
					(size 1.27 1.27)
				)
			)
		)
		(duplicate_pad_numbers_are_jumpers no)
		(fp_line
			(start -1.949958 1.610106)
			(end -1.949958 -1.610106)
			(stroke
				(width 0.1524)
				(type default)
			)
			(layer "F.SilkS")
		)
		(fp_line
			(start 1.949958 1.610106)
			(end -1.949958 1.610106)
			(stroke
				(width 0.1524)
				(type default)
			)
			(layer "F.SilkS")
		)
		(fp_line
			(start 1.949958 -1.560068)
			(end 1.949958 1.610106)
			(stroke
				(width 0.1524)
				(type default)
			)
			(layer "F.SilkS")
		)
		(fp_line
			(start -1.949958 -1.610106)
			(end 1.949958 -1.610106)
			(stroke
				(width 0.1524)
				(type default)
			)
			(layer "F.SilkS")
		)
		(fp_line
			(start -0.750062 1.560068)
			(end -0.750062 -1.560068)
			(stroke
				(width 0.1)
				(type default)
			)
			(layer "F.Fab")
		)
		(fp_line
			(start 0.750062 1.560068)
			(end -0.750062 1.560068)
			(stroke
				(width 0.1)
				(type default)
			)
			(layer "F.Fab")
		)
		(fp_line
			(start -0.750062 -1.560068)
			(end 0.750062 -1.560068)
			(stroke
				(width 0.1)
				(type default)
			)
			(layer "F.Fab")
		)
		(fp_line
			(start 0.750062 -1.560068)
			(end 0.750062 1.560068)
			(stroke
				(width 0.1)
				(type default)
			)
			(layer "F.Fab")
		)
		(pad "D" smd rect
			(at 1.100074 0 180)
			(size 1.016 1.4224)
			(layers "F.Cu" "F.Mask" "F.Paste")
			(net "SSD6_LED_ISO_N")
		)
		(pad "G" smd rect
			(at -1.100074 -0.94996 180)
			(size 1.016 1.4224)
			(layers "F.Cu" "F.Mask" "F.Paste")
			(net "SSD6_LED_R")
		)
		(pad "S" smd rect
			(at -1.100074 0.94996 180)
			(size 1.016 1.4224)
			(layers "F.Cu" "F.Mask" "F.Paste")
			(net "GND")
		)
	)
	(footprint ""
		(layer "F.Cu")
		(at 349.899986 -194.360038)
		(property "Reference" "H68"
			(at -4.485894 -5.045456 0)
			(unlocked yes)
			(layer "F.SilkS")
			(effects
				(font
					(size 0.7874 0.5842)
					(thickness 0.1524)
				)
				(justify left)
			)
		)
		(property "Value" ""
			(at 0 0 0)
			(layer "F.Fab")
			(effects
				(font
					(size 1.27 1.27)
				)
			)
		)
		(duplicate_pad_numbers_are_jumpers no)
		(pad "1" thru_hole circle
			(at 0 0)
			(size 10.0076 10.0076)
			(drill 5.6134)
			(layers "*.Cu" "*.Mask")
			(remove_unused_layers no)
			(net "GND")
			(clearance -1.9431)
		)
	)
	(footprint ""
		(layer "F.Cu")
		(at 270.960342 -97.1804 180)
		(property "Reference" "R212"
			(at 0 0 180)
			(layer "F.SilkS")
			(hide yes)
			(effects
				(font
					(size 1.27 1.27)
				)
			)
		)
		(property "Value" ""
			(at 0 0 180)
			(layer "F.Fab")
			(effects
				(font
					(size 1.27 1.27)
				)
			)
		)
		(duplicate_pad_numbers_are_jumpers no)
		(fp_line
			(start 0.7874 0.4064)
			(end -0.7874 0.4064)
			(stroke
				(width 0.1524)
				(type default)
			)
			(layer "F.SilkS")
		)
		(fp_line
			(start 0.7874 -0.4064)
			(end 0.7874 0.4064)
			(stroke
				(width 0.1524)
				(type default)
			)
			(layer "F.SilkS")
		)
		(fp_line
			(start -0.7874 0.4064)
			(end -0.7874 -0.4064)
			(stroke
				(width 0.1524)
				(type default)
			)
			(layer "F.SilkS")
		)
		(fp_line
			(start -0.7874 -0.4064)
			(end 0.7874 -0.4064)
			(stroke
				(width 0.1524)
				(type default)
			)
			(layer "F.SilkS")
		)
		(fp_line
			(start 0.67945 0.3048)
			(end 0.120396 0.3048)
			(stroke
				(width 0.1)
				(type default)
			)
			(layer "F.Fab")
		)
		(fp_line
			(start 0.67945 -0.3048)
			(end 0.67945 0.3048)
			(stroke
				(width 0.1)
				(type default)
			)
			(layer "F.Fab")
		)
		(fp_line
			(start 0.12065 -0.2794)
			(end 0.12065 -0.3048)
			(stroke
				(width 0.1)
				(type default)
			)
			(layer "F.Fab")
		)
		(fp_line
			(start 0.12065 -0.3048)
			(end 0.67945 -0.3048)
			(stroke
				(width 0.1)
				(type default)
			)
			(layer "F.Fab")
		)
		(fp_line
			(start 0.120396 0.3048)
			(end 0.120396 0.2794)
			(stroke
				(width 0.1)
				(type default)
			)
			(layer "F.Fab")
		)
		(fp_line
			(start 0.120396 0.2794)
			(end -0.12065 0.2794)
			(stroke
				(width 0.1)
				(type default)
			)
			(layer "F.Fab")
		)
		(fp_line
			(start -0.12065 0.3048)
			(end -0.67945 0.3048)
			(stroke
				(width 0.1)
				(type default)
			)
			(layer "F.Fab")
		)
		(fp_line
			(start -0.12065 0.2794)
			(end -0.12065 0.3048)
			(stroke
				(width 0.1)
				(type default)
			)
			(layer "F.Fab")
		)
		(fp_line
			(start -0.12065 -0.2794)
			(end 0.12065 -0.2794)
			(stroke
				(width 0.1)
				(type default)
			)
			(layer "F.Fab")
		)
		(fp_line
			(start -0.12065 -0.305054)
			(end -0.12065 -0.2794)
			(stroke
				(width 0.1)
				(type default)
			)
			(layer "F.Fab")
		)
		(fp_line
			(start -0.67945 0.3048)
			(end -0.67945 -0.305054)
			(stroke
				(width 0.1)
				(type default)
			)
			(layer "F.Fab")
		)
		(fp_line
			(start -0.67945 -0.305054)
			(end -0.12065 -0.305054)
			(stroke
				(width 0.1)
				(type default)
			)
			(layer "F.Fab")
		)
		(pad "1" smd circle
			(at -0.40005 0 180)
			(size 0 0)
			(layers "F.Cu" "F.Mask" "F.Paste")
			(net "PRSNTB3_NIC4_N")
		)
		(pad "2" smd circle
			(at 0.40005 0 180)
			(size 0 0)
			(layers "F.Cu" "F.Mask" "F.Paste")
			(net "P3V3_AUX")
		)
	)
)
